(kicad_pcb
	(version 20260206)
	(generator "pcbnew")
	(generator_version "10.0")
	(general
		(thickness 1.6)
		(legacy_teardrops no)
	)
	(paper "A4")
	(title_block
		(title "Wiwynn_Tioga_Pass_MB.brd")
		(comment 1 "Tioga Pass / footprint 830 of 4770 (J1A1), pads 244-291 of 291")
	)
	(layers
		(0 "F.Cu" signal "TOP")
		(4 "In1.Cu" signal "L2GND")
		(6 "In2.Cu" signal "L3")
		(8 "In3.Cu" signal "L4GND")
		(10 "In4.Cu" signal "L5")
		(12 "In5.Cu" signal "L6GND")
		(14 "In6.Cu" signal "L7VCC")
		(16 "In7.Cu" signal "L8VCC")
		(18 "In8.Cu" signal "L9GND")
		(20 "In9.Cu" signal "L10")
		(22 "In10.Cu" signal "L11GND")
		(24 "In11.Cu" signal "L12")
		(26 "In12.Cu" signal "L13GND")
		(2 "B.Cu" signal "BOTTOM")
		(9 "F.Adhes" user "F.Adhesive")
		(11 "B.Adhes" user "B.Adhesive")
		(13 "F.Paste" user "Package Geometry/Pastemask Top")
		(15 "B.Paste" user "Package Geometry/Pastemask Bottom")
		(5 "F.SilkS" user "Ref Des/Silkscreen Top")
		(7 "B.SilkS" user "Ref Des/Silkscreen Bottom")
		(1 "F.Mask" user "Board Geometry/Soldermask Top")
		(3 "B.Mask" user "Board Geometry/Soldermask Bottom")
		(17 "Dwgs.User" user "User.Drawings")
		(19 "Cmts.User" user "User.Comments")
		(21 "Eco1.User" user "User.Eco1")
		(23 "Eco2.User" user "User.Eco2")
		(25 "Edge.Cuts" user "Board Geometry/Outline")
		(27 "Margin" user)
		(31 "F.CrtYd" user "Package Geometry/Place Bound Top")
		(29 "B.CrtYd" user "Package Geometry/Place Bound Bottom")
		(35 "F.Fab" user "Ref Des/Assembly Top")
		(33 "B.Fab" user "Ref Des/Assembly Bottom")
	)
	(footprint ""
		(layer "F.Cu")
		(at 29.699458 -152.273 90)
		(property "Reference" "J1A1"
			(at -2.572512 42.563542 0)
			(unlocked yes)
			(layer "F.SilkS")
			(effects
				(font
					(size 0.7874 0.5842)
					(thickness 0.1524)
				)
				(justify left)
			)
		)
		(property "Value" ""
			(at 0 0 90)
			(layer "F.Fab")
			(effects
				(font
					(size 1.27 1.27)
				)
			)
		)
		(duplicate_pad_numbers_are_jumpers no)
		(pad "241" smd rect
			(at 4.59994 86.700106 90)
			(size 1.8034 0.508)
			(layers "F.Cu" "F.Mask" "F.Paste")
			(net "GND")
		)
		(pad "242" smd rect
			(at 4.59994 87.54999 90)
			(size 1.8034 0.508)
			(layers "F.Cu" "F.Mask" "F.Paste")
			(net "M_M_DQ<32>")
		)
		(pad "243" smd rect
			(at 4.59994 88.399874 90)
			(size 1.8034 0.508)
			(layers "F.Cu" "F.Mask" "F.Paste")
			(net "GND")
		)
		(pad "244" smd rect
			(at 4.59994 89.250012 90)
			(size 1.8034 0.508)
			(layers "F.Cu" "F.Mask" "F.Paste")
			(net "M_M_DQS_DN<4>")
		)
		(pad "245" smd rect
			(at 4.59994 90.099896 90)
			(size 1.8034 0.508)
			(layers "F.Cu" "F.Mask" "F.Paste")
			(net "M_M_DQS_DP<4>")
		)
		(pad "246" smd rect
			(at 4.59994 90.950034 90)
			(size 1.8034 0.508)
			(layers "F.Cu" "F.Mask" "F.Paste")
			(net "GND")
		)
		(pad "247" smd rect
			(at 4.59994 91.799918 90)
			(size 1.8034 0.508)
			(layers "F.Cu" "F.Mask" "F.Paste")
			(net "M_M_DQ<38>")
		)
		(pad "248" smd rect
			(at 4.59994 92.650056 90)
			(size 1.8034 0.508)
			(layers "F.Cu" "F.Mask" "F.Paste")
			(net "GND")
		)
		(pad "249" smd rect
			(at 4.59994 93.49994 90)
			(size 1.8034 0.508)
			(layers "F.Cu" "F.Mask" "F.Paste")
			(net "M_M_DQ<34>")
		)
		(pad "250" smd rect
			(at 4.59994 94.350078 90)
			(size 1.8034 0.508)
			(layers "F.Cu" "F.Mask" "F.Paste")
			(net "GND")
		)
		(pad "251" smd rect
			(at 4.59994 95.199962 90)
			(size 1.8034 0.508)
			(layers "F.Cu" "F.Mask" "F.Paste")
			(net "M_M_DQ<44>")
		)
		(pad "252" smd rect
			(at 4.59994 96.0501 90)
			(size 1.8034 0.508)
			(layers "F.Cu" "F.Mask" "F.Paste")
			(net "GND")
		)
		(pad "253" smd rect
			(at 4.59994 96.899984 90)
			(size 1.8034 0.508)
			(layers "F.Cu" "F.Mask" "F.Paste")
			(net "M_M_DQ<40>")
		)
		(pad "254" smd rect
			(at 4.59994 97.750122 90)
			(size 1.8034 0.508)
			(layers "F.Cu" "F.Mask" "F.Paste")
			(net "GND")
		)
		(pad "255" smd rect
			(at 4.59994 98.600006 90)
			(size 1.8034 0.508)
			(layers "F.Cu" "F.Mask" "F.Paste")
			(net "M_M_DQS_DN<5>")
		)
		(pad "256" smd rect
			(at 4.59994 99.44989 90)
			(size 1.8034 0.508)
			(layers "F.Cu" "F.Mask" "F.Paste")
			(net "M_M_DQS_DP<5>")
		)
		(pad "257" smd rect
			(at 4.59994 100.300028 90)
			(size 1.8034 0.508)
			(layers "F.Cu" "F.Mask" "F.Paste")
			(net "GND")
		)
		(pad "258" smd rect
			(at 4.59994 101.149912 90)
			(size 1.8034 0.508)
			(layers "F.Cu" "F.Mask" "F.Paste")
			(net "M_M_DQ<46>")
		)
		(pad "259" smd rect
			(at 4.59994 102.00005 90)
			(size 1.8034 0.508)
			(layers "F.Cu" "F.Mask" "F.Paste")
			(net "GND")
		)
		(pad "260" smd rect
			(at 4.59994 102.849934 90)
			(size 1.8034 0.508)
			(layers "F.Cu" "F.Mask" "F.Paste")
			(net "M_M_DQ<42>")
		)
		(pad "261" smd rect
			(at 4.59994 103.700072 90)
			(size 1.8034 0.508)
			(layers "F.Cu" "F.Mask" "F.Paste")
			(net "GND")
		)
		(pad "262" smd rect
			(at 4.59994 104.549956 90)
			(size 1.8034 0.508)
			(layers "F.Cu" "F.Mask" "F.Paste")
			(net "M_M_DQ<52>")
		)
		(pad "263" smd rect
			(at 4.59994 105.400094 90)
			(size 1.8034 0.508)
			(layers "F.Cu" "F.Mask" "F.Paste")
			(net "GND")
		)
		(pad "264" smd rect
			(at 4.59994 106.249978 90)
			(size 1.8034 0.508)
			(layers "F.Cu" "F.Mask" "F.Paste")
			(net "M_M_DQ<48>")
		)
		(pad "265" smd rect
			(at 4.59994 107.100116 90)
			(size 1.8034 0.508)
			(layers "F.Cu" "F.Mask" "F.Paste")
			(net "GND")
		)
		(pad "266" smd rect
			(at 4.59994 107.95 90)
			(size 1.8034 0.508)
			(layers "F.Cu" "F.Mask" "F.Paste")
			(net "M_M_DQS_DN<6>")
		)
		(pad "267" smd rect
			(at 4.59994 108.799884 90)
			(size 1.8034 0.508)
			(layers "F.Cu" "F.Mask" "F.Paste")
			(net "M_M_DQS_DP<6>")
		)
		(pad "268" smd rect
			(at 4.59994 109.650022 90)
			(size 1.8034 0.508)
			(layers "F.Cu" "F.Mask" "F.Paste")
			(net "GND")
		)
		(pad "269" smd rect
			(at 4.59994 110.499906 90)
			(size 1.8034 0.508)
			(layers "F.Cu" "F.Mask" "F.Paste")
			(net "M_M_DQ<54>")
		)
		(pad "270" smd rect
			(at 4.59994 111.350044 90)
			(size 1.8034 0.508)
			(layers "F.Cu" "F.Mask" "F.Paste")
			(net "GND")
		)
		(pad "271" smd rect
			(at 4.59994 112.199928 90)
			(size 1.8034 0.508)
			(layers "F.Cu" "F.Mask" "F.Paste")
			(net "M_M_DQ<50>")
		)
		(pad "272" smd rect
			(at 4.59994 113.050066 90)
			(size 1.8034 0.508)
			(layers "F.Cu" "F.Mask" "F.Paste")
			(net "GND")
		)
		(pad "273" smd rect
			(at 4.59994 113.89995 90)
			(size 1.8034 0.508)
			(layers "F.Cu" "F.Mask" "F.Paste")
			(net "M_M_DQ<60>")
		)
		(pad "274" smd rect
			(at 4.59994 114.750088 90)
			(size 1.8034 0.508)
			(layers "F.Cu" "F.Mask" "F.Paste")
			(net "GND")
		)
		(pad "275" smd rect
			(at 4.59994 115.599972 90)
			(size 1.8034 0.508)
			(layers "F.Cu" "F.Mask" "F.Paste")
			(net "M_M_DQ<56>")
		)
		(pad "276" smd rect
			(at 4.59994 116.45011 90)
			(size 1.8034 0.508)
			(layers "F.Cu" "F.Mask" "F.Paste")
			(net "GND")
		)
		(pad "277" smd rect
			(at 4.59994 117.299994 90)
			(size 1.8034 0.508)
			(layers "F.Cu" "F.Mask" "F.Paste")
			(net "M_M_DQS_DN<7>")
		)
		(pad "278" smd rect
			(at 4.59994 118.149878 90)
			(size 1.8034 0.508)
			(layers "F.Cu" "F.Mask" "F.Paste")
			(net "M_M_DQS_DP<7>")
		)
		(pad "279" smd rect
			(at 4.59994 119.000016 90)
			(size 1.8034 0.508)
			(layers "F.Cu" "F.Mask" "F.Paste")
			(net "GND")
		)
		(pad "280" smd rect
			(at 4.59994 119.8499 90)
			(size 1.8034 0.508)
			(layers "F.Cu" "F.Mask" "F.Paste")
			(net "M_M_DQ<62>")
		)
		(pad "281" smd rect
			(at 4.59994 120.700038 90)
			(size 1.8034 0.508)
			(layers "F.Cu" "F.Mask" "F.Paste")
			(net "GND")
		)
		(pad "282" smd rect
			(at 4.59994 121.549922 90)
			(size 1.8034 0.508)
			(layers "F.Cu" "F.Mask" "F.Paste")
			(net "M_M_DQ<58>")
		)
		(pad "283" smd rect
			(at 4.59994 122.40006 90)
			(size 1.8034 0.508)
			(layers "F.Cu" "F.Mask" "F.Paste")
			(net "GND")
		)
		(pad "284" smd rect
			(at 4.59994 123.249944 90)
			(size 1.8034 0.508)
			(layers "F.Cu" "F.Mask" "F.Paste")
			(net "PVPP_KLM")
		)
		(pad "285" smd rect
			(at 4.59994 124.100082 90)
			(size 1.8034 0.508)
			(layers "F.Cu" "F.Mask" "F.Paste")
			(net "SMB_DDR_KLM_VPP_SDA")
		)
		(pad "286" smd rect
			(at 4.59994 124.949966 90)
			(size 1.8034 0.508)
			(layers "F.Cu" "F.Mask" "F.Paste")
			(net "PVPP_KLM")
		)
		(pad "287" smd rect
			(at 4.59994 125.800104 90)
			(size 1.8034 0.508)
			(layers "F.Cu" "F.Mask" "F.Paste")
			(net "PVPP_KLM")
		)
		(pad "288" smd rect
			(at 4.59994 126.649988 90)
			(size 1.8034 0.508)
			(layers "F.Cu" "F.Mask" "F.Paste")
			(net "PVPP_KLM")
		)
	)
)
